#ISCELL
  pure_quanta quanta_title_block_c *
  *
#ISCELL
  standard offpage *
  page212_i1
#CELL
  pure_quanta q_res *
  page212_i10
#ISCELL
  standard offpage *
  page212_i100
#CELL
  pure_quanta q_res *
  page212_i105
#ISCELL
  standard offpage *
  page212_i111
#CELL
  pure_quanta q_res *
  page212_i113
#ISCELL
  standard offpage *
  page212_i126
#CELL
  pure_quanta q_res *
  page212_i127
#ISCELL
  standard offpage *
  page212_i128
#CELL
  pure_quanta q_res *
  page212_i129
#ISCELL
  standard offpage *
  page212_i13
#CELL
  pure_quanta q_res *
  page212_i130
#ISCELL
  standard offpage *
  page212_i131
#ISCELL
  standard offpage *
  page212_i14
#CELL
  pure_quanta q_res *
  page212_i15
#ISCELL
  standard offpage *
  page212_i16
#CELL
  pure_quanta q_res *
  page212_i17
#ISCELL
  standard offpage *
  page212_i18
#CELL
  pure_quanta mosfet_n *
  page212_i19
#ISCELL
  standard offpage *
  page212_i2
#ISCELL
  standard offpage *
  page212_i20
#CELL
  pure_quanta q_res *
  page212_i24
#ISCELL
  logical_power universal_power *
  page212_i25
#ISCELL
  logical_power universal_gnd *
  page212_i26
#CELL
  pure_quanta q_res *
  page212_i27
#ISCELL
  standard offpage *
  page212_i28
#ISCELL
  standard offpage *
  page212_i42
#ISCELL
  standard offpage *
  page212_i43
#CELL
  pure_quanta q_res *
  page212_i44
#ISCELL
  standard offpage *
  page212_i45
#ISCELL
  standard offpage *
  page212_i46
#ISCELL
  standard offpage *
  page212_i49
#ISCELL
  standard offpage *
  page212_i5
#ISCELL
  standard offpage *
  page212_i53
#ISCELL
  standard offpage *
  page212_i54
#CELL
  pure_quanta q_res *
  page212_i55
#CELL
  pure_quanta q_res *
  page212_i56
#ISCELL
  standard offpage *
  page212_i57
#ISCELL
  standard offpage *
  page212_i59
#ISCELL
  standard offpage *
  page212_i6
#CELL
  pure_quanta q_res *
  page212_i7
#ISCELL
  standard offpage *
  page212_i73
#ISCELL
  standard offpage *
  page212_i8
#CELL
  pure_quanta q_res *
  page212_i86
#CELL
  pure_quanta q_res *
  page212_i87
#ISCELL
  standard offpage *
  page212_i88
#ISCELL
  standard offpage *
  page212_i9
#ISCELL
  standard offpage *
  page212_i90
#CELL
  pure_quanta q_res *
  page212_i91
#CELL
  pure_quanta q_res *
  page212_i92
#ISCELL
  logical_power universal_gnd *
  page212_i93
#CELL
  pure_quanta q_res *
  page212_i94
#ISCELL
  standard offpage *
  page212_i95
#ISCELL
  standard offpage *
  page212_i96
#ISCELL
  standard offpage *
  page212_i97
